# S9S_MB_2U (Grand Teton) — schematic netlist excerpt (pin names and nets, part order shuffled) for the footprints in the layout excerpt that follows; sources: Cadence DE-HDL packaged netlist, KiCad conversion of 03242023_DA0F0TMBIJ0_F0T_Motherboard_J_brd_V01_OCP.brd

R3274  Q_RES  68K 1% EMPTY  pkg 0402LF  page 166 : A = FM_P2E_EQA0 ; B = GND
PC415  Q_CAPP  560UF 2.5V 20% OSCON  pkg THLF  page 289 : A = PVCCFA_EHV_FIVRA_CPU1 ; B = GND
R3048  Q_RES  0 5% CHIP  pkg 0402LF  page 214 : A = MB0_P12V_STBY_PWRGD ; B = PWRGD_PS_PWROK

(kicad_pcb
	(version 20260206)
	(generator "pcbnew")
	(generator_version "10.0")
	(general
		(thickness 1.6)
		(legacy_teardrops no)
	)
	(paper "A4")
	(title_block
		(title "03242023_DA0F0TMBIJ0_F0T_Motherboard_J_brd_V01_OCP.brd")
		(comment 1 "Grand Teton / footprints 1425-1427 of 6105")
	)
	(layers
		(0 "F.Cu" signal "TOP")
		(4 "In1.Cu" signal "GND")
		(6 "In2.Cu" signal "IN1")
		(8 "In3.Cu" signal "GND1")
		(10 "In4.Cu" signal "IN2")
		(12 "In5.Cu" signal "GND2")
		(14 "In6.Cu" signal "IN3")
		(16 "In7.Cu" signal "GND3")
		(18 "In8.Cu" signal "VCC")
		(20 "In9.Cu" signal "VCC1")
		(22 "In10.Cu" signal "GND4")
		(24 "In11.Cu" signal "IN4")
		(26 "In12.Cu" signal "GND5")
		(28 "In13.Cu" signal "IN5")
		(30 "In14.Cu" signal "GND6")
		(32 "In15.Cu" signal "IN6")
		(34 "In16.Cu" signal "GND7")
		(2 "B.Cu" signal "BOTTOM")
		(9 "F.Adhes" user "F.Adhesive")
		(11 "B.Adhes" user "B.Adhesive")
		(13 "F.Paste" user "Package Geometry/Pastemask Top")
		(15 "B.Paste" user "Package Geometry/Pastemask Bottom")
		(5 "F.SilkS" user "Ref Des/Silkscreen Top")
		(7 "B.SilkS" user "Ref Des/Silkscreen Bottom")
		(1 "F.Mask" user "Board Geometry/Soldermask Top")
		(3 "B.Mask" user "Board Geometry/Soldermask Bottom")
		(17 "Dwgs.User" user "User.Drawings")
		(19 "Cmts.User" user "User.Comments")
		(21 "Eco1.User" user "User.Eco1")
		(23 "Eco2.User" user "User.Eco2")
		(25 "Edge.Cuts" user "Board Geometry/Outline")
		(27 "Margin" user)
		(31 "F.CrtYd" user "Package Geometry/Place Bound Top")
		(29 "B.CrtYd" user "Package Geometry/Place Bound Bottom")
		(35 "F.Fab" user "Ref Des/Assembly Top")
		(33 "B.Fab" user "Ref Des/Assembly Bottom")
	)
	(footprint ""
		(layer "F.Cu")
		(at 22.364192 -399.532094 90)
		(property "Reference" "R3274"
			(at 0 0 90)
			(layer "F.SilkS")
			(hide yes)
			(effects
				(font
					(size 1.27 1.27)
				)
			)
		)
		(property "Value" ""
			(at 0 0 90)
			(layer "F.Fab")
			(effects
				(font
					(size 1.27 1.27)
				)
			)
		)
		(duplicate_pad_numbers_are_jumpers no)
		(fp_line
			(start 0.7874 -0.4064)
			(end 0.7874 0.4064)
			(stroke
				(width 0.1524)
				(type default)
			)
			(layer "F.SilkS")
		)
		(fp_line
			(start -0.7874 -0.4064)
			(end 0.7874 -0.4064)
			(stroke
				(width 0.1524)
				(type default)
			)
			(layer "F.SilkS")
		)
		(fp_line
			(start 0.7874 0.4064)
			(end -0.7874 0.4064)
			(stroke
				(width 0.1524)
				(type default)
			)
			(layer "F.SilkS")
		)
		(fp_line
			(start -0.7874 0.4064)
			(end -0.7874 -0.4064)
			(stroke
				(width 0.1524)
				(type default)
			)
			(layer "F.SilkS")
		)
		(fp_line
			(start -0.12065 -0.305054)
			(end -0.12065 -0.2794)
			(stroke
				(width 0.1)
				(type default)
			)
			(layer "F.Fab")
		)
		(fp_line
			(start -0.67945 -0.305054)
			(end -0.12065 -0.305054)
			(stroke
				(width 0.1)
				(type default)
			)
			(layer "F.Fab")
		)
		(fp_line
			(start 0.67945 -0.3048)
			(end 0.67945 0.3048)
			(stroke
				(width 0.1)
				(type default)
			)
			(layer "F.Fab")
		)
		(fp_line
			(start 0.12065 -0.3048)
			(end 0.67945 -0.3048)
			(stroke
				(width 0.1)
				(type default)
			)
			(layer "F.Fab")
		)
		(fp_line
			(start 0.12065 -0.2794)
			(end 0.12065 -0.3048)
			(stroke
				(width 0.1)
				(type default)
			)
			(layer "F.Fab")
		)
		(fp_line
			(start -0.12065 -0.2794)
			(end 0.12065 -0.2794)
			(stroke
				(width 0.1)
				(type default)
			)
			(layer "F.Fab")
		)
		(fp_line
			(start 0.120396 0.2794)
			(end -0.12065 0.2794)
			(stroke
				(width 0.1)
				(type default)
			)
			(layer "F.Fab")
		)
		(fp_line
			(start -0.12065 0.2794)
			(end -0.12065 0.3048)
			(stroke
				(width 0.1)
				(type default)
			)
			(layer "F.Fab")
		)
		(fp_line
			(start 0.67945 0.3048)
			(end 0.120396 0.3048)
			(stroke
				(width 0.1)
				(type default)
			)
			(layer "F.Fab")
		)
		(fp_line
			(start 0.120396 0.3048)
			(end 0.120396 0.2794)
			(stroke
				(width 0.1)
				(type default)
			)
			(layer "F.Fab")
		)
		(fp_line
			(start -0.12065 0.3048)
			(end -0.67945 0.3048)
			(stroke
				(width 0.1)
				(type default)
			)
			(layer "F.Fab")
		)
		(fp_line
			(start -0.67945 0.3048)
			(end -0.67945 -0.305054)
			(stroke
				(width 0.1)
				(type default)
			)
			(layer "F.Fab")
		)
		(pad "1" smd circle
			(at -0.40005 0 90)
			(size 0 0)
			(layers "F.Cu" "F.Mask" "F.Paste")
			(net "FM_P2E_EQA0")
		)
		(pad "2" smd circle
			(at 0.40005 0 90)
			(size 0 0)
			(layers "F.Cu" "F.Mask" "F.Paste")
			(net "GND")
		)
	)
	(footprint ""
		(layer "F.Cu")
		(at 46.697138 -337.477608)
		(property "Reference" "PC415"
			(at 0 0 0)
			(layer "F.SilkS")
			(hide yes)
			(effects
				(font
					(size 1.27 1.27)
				)
			)
		)
		(property "Value" ""
			(at 0 0 0)
			(layer "F.Fab")
			(effects
				(font
					(size 1.27 1.27)
				)
			)
		)
		(duplicate_pad_numbers_are_jumpers no)
		(fp_line
			(start 2.750058 0.999998)
			(end -2.750058 0.999998)
			(stroke
				(width 0.1524)
				(type default)
			)
			(layer "F.SilkS")
		)
		(fp_circle
			(center 0 0.999998)
			(end 2.750058 0.999998)
			(stroke
				(width 0.1524)
				(type default)
			)
			(fill no)
			(layer "F.SilkS")
		)
		(fp_poly
			(pts
				(arc
					(start 2.750058 0.999998)
					(mid 0 3.750056)
					(end -2.750058 0.999998)
				)
			)
			(stroke
				(width 0)
				(type default)
			)
			(fill yes)
			(layer "F.SilkS")
		)
		(fp_circle
			(center 0 0.999998)
			(end 2.750058 0.999998)
			(stroke
				(width 0.1)
				(type default)
			)
			(fill no)
			(layer "F.Fab")
		)
		(pad "1" thru_hole rect
			(at 0 0)
			(size 1.5748 1.5748)
			(drill 1.0668)
			(layers "*.Cu" "*.Mask")
			(remove_unused_layers no)
			(net "PVCCFA_EHV_FIVRA_CPU1")
			(clearance 0)
			(padstack
				(mode front_inner_back)
				(layer "Inner"
					(shape circle)
					(size 1.5748 1.5748)
					(clearance 0)
				)
				(layer "B.Cu"
					(shape rect)
					(size 1.5748 1.5748)
					(clearance 0)
				)
			)
		)
		(pad "2" thru_hole circle
			(at 0 1.999996)
			(size 1.5748 1.5748)
			(drill 1.0668)
			(layers "*.Cu" "*.Mask")
			(remove_unused_layers no)
			(net "GND")
			(clearance 0)
		)
	)
	(footprint ""
		(layer "F.Cu")
		(at 171.50588 -133.695948 -90)
		(property "Reference" "R3048"
			(at 0 0 270)
			(layer "F.SilkS")
			(hide yes)
			(effects
				(font
					(size 1.27 1.27)
				)
			)
		)
		(property "Value" ""
			(at 0 0 270)
			(layer "F.Fab")
			(effects
				(font
					(size 1.27 1.27)
				)
			)
		)
		(duplicate_pad_numbers_are_jumpers no)
		(fp_line
			(start -0.7874 0.4064)
			(end -0.7874 -0.4064)
			(stroke
				(width 0.1524)
				(type default)
			)
			(layer "F.SilkS")
		)
		(fp_line
			(start 0.7874 0.4064)
			(end -0.7874 0.4064)
			(stroke
				(width 0.1524)
				(type default)
			)
			(layer "F.SilkS")
		)
		(fp_line
			(start -0.7874 -0.4064)
			(end 0.7874 -0.4064)
			(stroke
				(width 0.1524)
				(type default)
			)
			(layer "F.SilkS")
		)
		(fp_line
			(start 0.7874 -0.4064)
			(end 0.7874 0.4064)
			(stroke
				(width 0.1524)
				(type default)
			)
			(layer "F.SilkS")
		)
		(fp_line
			(start -0.67945 0.3048)
			(end -0.67945 -0.305054)
			(stroke
				(width 0.1)
				(type default)
			)
			(layer "F.Fab")
		)
		(fp_line
			(start -0.12065 0.3048)
			(end -0.67945 0.3048)
			(stroke
				(width 0.1)
				(type default)
			)
			(layer "F.Fab")
		)
		(fp_line
			(start 0.120396 0.3048)
			(end 0.120396 0.2794)
			(stroke
				(width 0.1)
				(type default)
			)
			(layer "F.Fab")
		)
		(fp_line
			(start 0.67945 0.3048)
			(end 0.120396 0.3048)
			(stroke
				(width 0.1)
				(type default)
			)
			(layer "F.Fab")
		)
		(fp_line
			(start -0.12065 0.2794)
			(end -0.12065 0.3048)
			(stroke
				(width 0.1)
				(type default)
			)
			(layer "F.Fab")
		)
		(fp_line
			(start 0.120396 0.2794)
			(end -0.12065 0.2794)
			(stroke
				(width 0.1)
				(type default)
			)
			(layer "F.Fab")
		)
		(fp_line
			(start -0.12065 -0.2794)
			(end 0.12065 -0.2794)
			(stroke
				(width 0.1)
				(type default)
			)
			(layer "F.Fab")
		)
		(fp_line
			(start 0.12065 -0.2794)
			(end 0.12065 -0.3048)
			(stroke
				(width 0.1)
				(type default)
			)
			(layer "F.Fab")
		)
		(fp_line
			(start 0.12065 -0.3048)
			(end 0.67945 -0.3048)
			(stroke
				(width 0.1)
				(type default)
			)
			(layer "F.Fab")
		)
		(fp_line
			(start 0.67945 -0.3048)
			(end 0.67945 0.3048)
			(stroke
				(width 0.1)
				(type default)
			)
			(layer "F.Fab")
		)
		(fp_line
			(start -0.67945 -0.305054)
			(end -0.12065 -0.305054)
			(stroke
				(width 0.1)
				(type default)
			)
			(layer "F.Fab")
		)
		(fp_line
			(start -0.12065 -0.305054)
			(end -0.12065 -0.2794)
			(stroke
				(width 0.1)
				(type default)
			)
			(layer "F.Fab")
		)
		(pad "1" smd circle
			(at -0.40005 0 270)
			(size 0 0)
			(layers "F.Cu" "F.Mask" "F.Paste")
			(net "MB0_P12V_STBY_PWRGD")
		)
		(pad "2" smd circle
			(at 0.40005 0 270)
			(size 0 0)
			(layers "F.Cu" "F.Mask" "F.Paste")
			(net "PWRGD_PS_PWROK")
		)
	)
)
